FILE_TYPE = MACRO_DRAWING;
SET COLOR_WIRE YELLOW;
SET COLOR_PROP MONO;
SET COLOR_DOT WHITE;
SET COLOR_ARC YELLOW;
SET COLOR_BODY GREEN;
SET COLOR_NOTE MONO;
SET PROP_DISPLAY VALUE;
SET PAGE_NUMBER P5;
FORCEADD INTEL_CORP_BPAGE..1
(12900 -100);
FORCEPROP 1 LAST CUSTOM_TXT_CDS <CURRENT_DESIGN_SHEET> OF <TOTAL_DESIGN_SHEETS>
J 0
(12400 -75);
PAINT GREEN (12400 -75);
FORCEPROP 1 LAST CUSTOM_TXT_CDS <CON_LAST_MODIFIED>
J 0
(10975 250);
PAINT GREEN (10975 250);
FORCEPROP 2 LAST CUSTOM_TXT_CDS <XR_PAGE_TITLE>
J 0
(5010 5150);
DISPLAY 0.638298 (5010 5150);
PAINT PINK (5010 5150);
DISPLAY INVISIBLE (5010 5150);
FORCEPROP 1 LAST SCH_ADDRESS1 2200 Mission College Blvd.
J 0
(8925 25);
DISPLAY 0.617021 (8925 25);
PAINT GREEN (8925 25);
FORCEPROP 1 LAST SCH_ADDRESS3 Santa Clara, CA 95052-8119
J 0
(8925 -75);
DISPLAY 0.617021 (8925 -75);
PAINT GREEN (8925 -75);
FORCEPROP 1 LAST SCH_REV 2.420
J 0
(12650 50);
DISPLAY 0.978723 (12650 50);
PAINT YELLOW (12650 50);
FORCEPROP 1 LAST SCH_ADDRESS2 P.O. BOX 58119
J 0
(8925 -25);
DISPLAY 0.617021 (8925 -25);
PAINT GREEN (8925 -25);
FORCEPROP 1 LAST SCH_TITLE SYSTEM BLOCK DIAGRAM
J 0
(4950 -50);
DISPLAY 1.212766 (4950 -50);
PAINT ORANGE (4950 -50);
FORCEPROP 1 LAST SCH_NUMBER H4694802
J 0
(11600 50);
DISPLAY 1.212766 (11600 50);
PAINT YELLOW (11600 50);
FORCEPROP 1 LAST SCH_DEPT BESD
J 1
(8450 0);
DISPLAY 1.212766 (8450 0);
PAINT YELLOW (8450 0);
FORCEPROP 2 LAST PAGE_BORDER TRUE
J 0
(5010 5150);
DISPLAY 0.638298 (5010 5150);
PAINT PINK (5010 5150);
DISPLAY INVISIBLE (5010 5150);
FORCEPROP 2 LAST CDS_LIB mstr_symbols
J 0
(12900 -100);
PAINT MONO (12900 -100);
DISPLAY INVISIBLE (12900 -100);
FORCEPROP 1 LAST COMMENT_BODY TRUE
J 0
(12912 -88);
DISPLAY 0.468085 (12912 -88);
PAINT GREEN (12912 -88);
DISPLAY INVISIBLE (12912 -88);
FORCEPROP 1 LAST CDS_CON_LAST_MODIFIED Tue Dec 01 11:47:56 2015
J 0
(11475 225);
PAINT ORANGE (11475 225);
DISPLAY INVISIBLE (11475 225);
FORCEPROP 2 LAST CDS_XR_PAGE_TITLE CR-5 : @BASEBOARD_FAB2_LIB.BASEBOARD_FAB2(SCH_1):PAGE5
J 0
(5010 5150);
DISPLAY 0.638298 (5010 5150);
PAINT PINK (5010 5150);
DISPLAY INVISIBLE (5010 5150);
FORCENOTE
$CDS_IMAGE|05_SYSTEM BLOCK DIAGRAM.jpg|5250|5250
(8400 2150) 0;
DISPLAY CENTER (8400 2150);
PAINT MONO (8400 2150);
QUIT
